(kicad_pcb
	(version 20260206)
	(generator "pcbnew")
	(generator_version "10.0")
	(general
		(thickness 1.6)
		(legacy_teardrops no)
	)
	(paper "A4")
	(title_block
		(title "peb — Lightning_PEB_BRD.brd")
		(comment 1 "Lightning (Wiwynn / Facebook NVMe JBOF) / footprints 963-966 of 2563")
	)
	(layers
		(0 "F.Cu" signal "TOP")
		(4 "In1.Cu" signal "L2GND")
		(6 "In2.Cu" signal "L3")
		(8 "In3.Cu" signal "L4VCC")
		(10 "In4.Cu" signal "L5VCC")
		(12 "In5.Cu" signal "L6")
		(14 "In6.Cu" signal "L7GND")
		(2 "B.Cu" signal "BOTTOM")
		(9 "F.Adhes" user "F.Adhesive")
		(11 "B.Adhes" user "B.Adhesive")
		(13 "F.Paste" user "Package Geometry/Pastemask Top")
		(15 "B.Paste" user "Package Geometry/Pastemask Bottom")
		(5 "F.SilkS" user "Ref Des/Silkscreen Top")
		(7 "B.SilkS" user "Ref Des/Silkscreen Bottom")
		(1 "F.Mask" user "Board Geometry/Soldermask Top")
		(3 "B.Mask" user "Board Geometry/Soldermask Bottom")
		(17 "Dwgs.User" user "User.Drawings")
		(19 "Cmts.User" user "User.Comments")
		(21 "Eco1.User" user "User.Eco1")
		(23 "Eco2.User" user "User.Eco2")
		(25 "Edge.Cuts" user "Board Geometry/Outline")
		(27 "Margin" user)
		(31 "F.CrtYd" user "Package Geometry/Place Bound Top")
		(29 "B.CrtYd" user "Package Geometry/Place Bound Bottom")
		(35 "F.Fab" user "Ref Des/Assembly Top")
		(33 "B.Fab" user "Ref Des/Assembly Bottom")
	)
	(footprint ""
		(layer "F.Cu")
		(at 192.5574 -8.9154 90)
		(property "Reference" "R683"
			(at 0 0 90)
			(layer "F.SilkS")
			(hide yes)
			(effects
				(font
					(size 1.27 1.27)
				)
			)
		)
		(property "Value" "0R2J-2-GP"
			(at 0.064008 -3.993896 90)
			(unlocked yes)
			(layer "F.Fab")
			(hide yes)
			(effects
				(font
					(size 1.016 1.016)
					(thickness 0.1524)
				)
			)
		)
		(property "Device Type" "R402H16"
			(at 0.064008 -5.517896 90)
			(unlocked yes)
			(layer "F.Fab")
			(hide yes)
			(effects
				(font
					(size 1.016 1.016)
					(thickness 0.1524)
				)
			)
		)
		(duplicate_pad_numbers_are_jumpers no)
		(fp_line
			(start 0.508 -0.9398)
			(end -0.508 -0.9398)
			(stroke
				(width 0.1524)
				(type default)
			)
			(layer "F.SilkS")
		)
		(fp_line
			(start -0.508 -0.9398)
			(end -0.508 0.9398)
			(stroke
				(width 0.1524)
				(type default)
			)
			(layer "F.SilkS")
		)
		(fp_rect
			(start -0.508 0.9398)
			(end 0.508 -0.9398)
			(stroke
				(width 0)
				(type default)
			)
			(fill no)
			(layer "F.CrtYd")
		)
		(fp_rect
			(start -0.508 0.9398)
			(end 0.508 -0.9398)
			(stroke
				(width 0)
				(type default)
			)
			(fill no)
			(layer "F.Fab")
		)
		(pad "1" smd custom
			(at 0 -0.4445 90)
			(size 0.1397 0.1397)
			(layers "F.Cu" "F.Mask" "F.Paste")
			(net "BMC_ENCLOSURE_LED_R")
			(options
				(clearance outline)
				(anchor circle)
			)
			(primitives
				(gr_poly
					(pts
						(arc
							(start -0.1778 -0.2794)
							(mid -0.249642 -0.249642)
							(end -0.2794 -0.1778)
						)
						(arc
							(start -0.2794 0.1778)
							(mid -0.249642 0.249642)
							(end -0.1778 0.2794)
						)
						(arc
							(start 0.1778 0.2794)
							(mid 0.249642 0.249642)
							(end 0.2794 0.1778)
						)
						(arc
							(start 0.2794 -0.1778)
							(mid 0.249642 -0.249642)
							(end 0.1778 -0.2794)
						)
					)
					(width 0)
					(fill yes)
				)
			)
		)
		(pad "2" smd custom
			(at 0 0.4445 90)
			(size 0.1397 0.1397)
			(layers "F.Cu" "F.Mask" "F.Paste")
			(net "BMC_ENCLOSURE_LED")
			(options
				(clearance outline)
				(anchor circle)
			)
			(primitives
				(gr_poly
					(pts
						(arc
							(start -0.1778 -0.2794)
							(mid -0.249642 -0.249642)
							(end -0.2794 -0.1778)
						)
						(arc
							(start -0.2794 0.1778)
							(mid -0.249642 0.249642)
							(end -0.1778 0.2794)
						)
						(arc
							(start 0.1778 0.2794)
							(mid 0.249642 0.249642)
							(end 0.2794 0.1778)
						)
						(arc
							(start 0.2794 -0.1778)
							(mid 0.249642 -0.249642)
							(end 0.1778 -0.2794)
						)
					)
					(width 0)
					(fill yes)
				)
			)
		)
	)
	(footprint ""
		(layer "F.Cu")
		(at 139.8016 -41.4782 180)
		(property "Reference" "R770"
			(at 0 0 180)
			(layer "F.SilkS")
			(hide yes)
			(effects
				(font
					(size 1.27 1.27)
				)
			)
		)
		(property "Value" "4K7R2F-GP"
			(at 0.064008 -3.993896 180)
			(unlocked yes)
			(layer "F.Fab")
			(hide yes)
			(effects
				(font
					(size 1.016 1.016)
					(thickness 0.1524)
				)
			)
		)
		(property "Device Type" "R402H16"
			(at 0.064008 -5.517896 180)
			(unlocked yes)
			(layer "F.Fab")
			(hide yes)
			(effects
				(font
					(size 1.016 1.016)
					(thickness 0.1524)
				)
			)
		)
		(duplicate_pad_numbers_are_jumpers no)
		(fp_line
			(start 0.508 -0.9398)
			(end -0.508 -0.9398)
			(stroke
				(width 0.1524)
				(type default)
			)
			(layer "F.SilkS")
		)
		(fp_line
			(start -0.508 -0.9398)
			(end -0.508 0.9398)
			(stroke
				(width 0.1524)
				(type default)
			)
			(layer "F.SilkS")
		)
		(fp_rect
			(start -0.508 0.9398)
			(end 0.508 -0.9398)
			(stroke
				(width 0)
				(type default)
			)
			(fill no)
			(layer "F.CrtYd")
		)
		(fp_rect
			(start -0.508 0.9398)
			(end 0.508 -0.9398)
			(stroke
				(width 0)
				(type default)
			)
			(fill no)
			(layer "F.Fab")
		)
		(pad "1" smd custom
			(at 0 -0.4445 180)
			(size 0.1397 0.1397)
			(layers "F.Cu" "F.Mask" "F.Paste")
			(net "DUT_VDDO")
			(options
				(clearance outline)
				(anchor circle)
			)
			(primitives
				(gr_poly
					(pts
						(arc
							(start -0.1778 -0.2794)
							(mid -0.249642 -0.249642)
							(end -0.2794 -0.1778)
						)
						(arc
							(start -0.2794 0.1778)
							(mid -0.249642 0.249642)
							(end -0.1778 0.2794)
						)
						(arc
							(start 0.1778 0.2794)
							(mid 0.249642 0.249642)
							(end 0.2794 0.1778)
						)
						(arc
							(start 0.2794 -0.1778)
							(mid 0.249642 -0.249642)
							(end 0.1778 -0.2794)
						)
					)
					(width 0)
					(fill yes)
				)
			)
		)
		(pad "2" smd custom
			(at 0 0.4445 180)
			(size 0.1397 0.1397)
			(layers "F.Cu" "F.Mask" "F.Paste")
			(net "EJTAG_TMS")
			(options
				(clearance outline)
				(anchor circle)
			)
			(primitives
				(gr_poly
					(pts
						(arc
							(start -0.1778 -0.2794)
							(mid -0.249642 -0.249642)
							(end -0.2794 -0.1778)
						)
						(arc
							(start -0.2794 0.1778)
							(mid -0.249642 0.249642)
							(end -0.1778 0.2794)
						)
						(arc
							(start 0.1778 0.2794)
							(mid 0.249642 0.249642)
							(end 0.2794 0.1778)
						)
						(arc
							(start 0.2794 -0.1778)
							(mid 0.249642 -0.249642)
							(end 0.1778 -0.2794)
						)
					)
					(width 0)
					(fill yes)
				)
			)
		)
	)
	(footprint ""
		(layer "F.Cu")
		(at 237.549944 -2.500122 180)
		(property "Reference" "CN3"
			(at 0 0 180)
			(layer "F.SilkS")
			(hide yes)
			(effects
				(font
					(size 1.27 1.27)
				)
			)
		)
		(property "Value" "JWT-CONN14A-1-GP"
			(at -9.8298 -4.064 180)
			(unlocked yes)
			(layer "F.Fab")
			(hide yes)
			(effects
				(font
					(size 1.016 1.016)
					(thickness 0.1524)
				)
			)
		)
		(property "Device Type" "A2005WR0-2CX7P-6T"
			(at -9.8298 -5.588 180)
			(unlocked yes)
			(layer "F.Fab")
			(hide yes)
			(effects
				(font
					(size 1.016 1.016)
					(thickness 0.1524)
				)
			)
		)
		(duplicate_pad_numbers_are_jumpers no)
		(fp_line
			(start 8.5852 -0.7366)
			(end 6.8834 -0.7366)
			(stroke
				(width 0.1524)
				(type default)
			)
			(layer "F.SilkS")
		)
		(fp_line
			(start 8.5852 -7.6454)
			(end 8.5852 -0.7366)
			(stroke
				(width 0.1524)
				(type default)
			)
			(layer "F.SilkS")
		)
		(fp_line
			(start 6.8834 1.8796)
			(end -6.8834 1.8796)
			(stroke
				(width 0.1524)
				(type default)
			)
			(layer "F.SilkS")
		)
		(fp_line
			(start 6.8834 -0.7366)
			(end 6.8834 1.8796)
			(stroke
				(width 0.1524)
				(type default)
			)
			(layer "F.SilkS")
		)
		(fp_line
			(start 1.1938 -7.6454)
			(end 1.1938 -7.1374)
			(stroke
				(width 0.1524)
				(type default)
			)
			(layer "F.SilkS")
		)
		(fp_line
			(start -1.1938 -7.1374)
			(end 1.1938 -7.1374)
			(stroke
				(width 0.1524)
				(type default)
			)
			(layer "F.SilkS")
		)
		(fp_line
			(start -1.1938 -7.6454)
			(end -1.1938 -7.1374)
			(stroke
				(width 0.1524)
				(type default)
			)
			(layer "F.SilkS")
		)
		(fp_line
			(start -5.1689 2.0574)
			(end -7.0739 2.0574)
			(stroke
				(width 0.508)
				(type default)
			)
			(layer "F.SilkS")
		)
		(fp_line
			(start -6.8834 1.8796)
			(end -6.8834 -0.7366)
			(stroke
				(width 0.1524)
				(type default)
			)
			(layer "F.SilkS")
		)
		(fp_line
			(start -6.8834 -0.7366)
			(end -8.5852 -0.7366)
			(stroke
				(width 0.1524)
				(type default)
			)
			(layer "F.SilkS")
		)
		(fp_line
			(start -7.0739 2.0574)
			(end -7.0739 0.1524)
			(stroke
				(width 0.508)
				(type default)
			)
			(layer "F.SilkS")
		)
		(fp_line
			(start -8.5852 -0.7366)
			(end -8.5852 -7.6454)
			(stroke
				(width 0.1524)
				(type default)
			)
			(layer "F.SilkS")
		)
		(fp_line
			(start -8.5852 -7.6454)
			(end 8.5852 -7.6454)
			(stroke
				(width 0.1524)
				(type default)
			)
			(layer "F.SilkS")
		)
		(fp_circle
			(center 5.99948 0.99949)
			(end 5.00888 0.99949)
			(stroke
				(width 0.3048)
				(type default)
			)
			(fill no)
			(layer "F.SilkS")
		)
		(fp_circle
			(center 5.99948 -0.99949)
			(end 5.00888 -0.99949)
			(stroke
				(width 0.3048)
				(type default)
			)
			(fill no)
			(layer "F.SilkS")
		)
		(fp_circle
			(center 4.0005 0.99949)
			(end 3.0099 0.99949)
			(stroke
				(width 0.3048)
				(type default)
			)
			(fill no)
			(layer "F.SilkS")
		)
		(fp_circle
			(center 4.0005 -0.99949)
			(end 3.0099 -0.99949)
			(stroke
				(width 0.3048)
				(type default)
			)
			(fill no)
			(layer "F.SilkS")
		)
		(fp_circle
			(center 2.00025 0.99949)
			(end 1.00965 0.99949)
			(stroke
				(width 0.3048)
				(type default)
			)
			(fill no)
			(layer "F.SilkS")
		)
		(fp_circle
			(center 2.00025 -0.99949)
			(end 1.00965 -0.99949)
			(stroke
				(width 0.3048)
				(type default)
			)
			(fill no)
			(layer "F.SilkS")
		)
		(fp_circle
			(center 0 0.99949)
			(end -0.9906 0.99949)
			(stroke
				(width 0.3048)
				(type default)
			)
			(fill no)
			(layer "F.SilkS")
		)
		(fp_circle
			(center 0 -0.99949)
			(end -0.9906 -0.99949)
			(stroke
				(width 0.3048)
				(type default)
			)
			(fill no)
			(layer "F.SilkS")
		)
		(fp_circle
			(center -2.00025 0.99949)
			(end -2.99085 0.99949)
			(stroke
				(width 0.3048)
				(type default)
			)
			(fill no)
			(layer "F.SilkS")
		)
		(fp_circle
			(center -2.00025 -0.99949)
			(end -2.99085 -0.99949)
			(stroke
				(width 0.3048)
				(type default)
			)
			(fill no)
			(layer "F.SilkS")
		)
		(fp_circle
			(center -4.0005 0.99949)
			(end -4.9911 0.99949)
			(stroke
				(width 0.3048)
				(type default)
			)
			(fill no)
			(layer "F.SilkS")
		)
		(fp_circle
			(center -4.0005 -0.99949)
			(end -4.9911 -0.99949)
			(stroke
				(width 0.3048)
				(type default)
			)
			(fill no)
			(layer "F.SilkS")
		)
		(fp_circle
			(center -5.99948 0.99949)
			(end -6.99008 0.99949)
			(stroke
				(width 0.3048)
				(type default)
			)
			(fill no)
			(layer "F.SilkS")
		)
		(fp_circle
			(center -5.99948 -0.99949)
			(end -6.99008 -0.99949)
			(stroke
				(width 0.3048)
				(type default)
			)
			(fill no)
			(layer "F.SilkS")
		)
		(fp_poly
			(pts
				(xy -6.2484 1.2446) (xy 6.2484 1.2446) (xy 6.2484 -0.9906) (xy 8.3312 -0.9906) (xy 8.3312 -7.3914)
				(xy -8.3312 -7.3914) (xy -8.3312 -0.9906) (xy -6.2484 -0.9906)
			)
			(stroke
				(width 0)
				(type default)
			)
			(fill no)
			(layer "F.CrtYd")
		)
		(fp_poly
			(pts
				(xy -7.1374 2.1336) (xy -7.1374 -0.4826) (xy -8.8392 -0.4826) (xy -8.8392 -7.8994) (xy 8.8392 -7.8994)
				(xy 8.8392 -0.4826) (xy 7.1374 -0.4826) (xy 7.1374 -0.00635) (xy 6.2484 -0.00635) (xy 6.2484 -0.9906)
				(xy 8.3312 -0.9906) (xy 8.3312 -7.3914) (xy -8.3312 -7.3914) (xy -8.3312 -0.9906) (xy -6.2484 -0.9906)
				(xy -6.2484 1.2446) (xy 6.2484 1.2446) (xy 6.2484 0.00635) (xy 7.1374 0.00635) (xy 7.1374 2.1336)
			)
			(stroke
				(width 0)
				(type default)
			)
			(fill no)
			(layer "F.CrtYd")
		)
		(fp_poly
			(pts
				(xy -7.1374 2.1336) (xy -7.1374 -0.4826) (xy -8.8392 -0.4826) (xy -8.8392 -7.8994) (xy 8.8392 -7.8994)
				(xy 8.8392 -0.4826) (xy 7.1374 -0.4826) (xy 7.1374 2.1336)
			)
			(stroke
				(width 0)
				(type default)
			)
			(fill no)
			(layer "F.Fab")
		)
		(pad "1" thru_hole circle
			(at -5.99948 0.99949 180)
			(size 1.27 1.27)
			(drill 0.889)
			(layers "*.Cu" "*.Mask")
			(remove_unused_layers no)
			(net "LOW_HEX_0")
			(clearance 0.1651)
			(thermal_gap 0.1651)
		)
		(pad "2" thru_hole circle
			(at -5.99948 -0.99949 180)
			(size 1.27 1.27)
			(drill 0.889)
			(layers "*.Cu" "*.Mask")
			(remove_unused_layers no)
			(net "LOW_HEX_1")
			(clearance 0.1651)
			(thermal_gap 0.1651)
		)
		(pad "3" thru_hole circle
			(at -4.0005 0.99949 180)
			(size 1.27 1.27)
			(drill 0.889)
			(layers "*.Cu" "*.Mask")
			(remove_unused_layers no)
			(net "LOW_HEX_2")
			(clearance 0.1651)
			(thermal_gap 0.1651)
		)
		(pad "4" thru_hole circle
			(at -4.0005 -0.99949 180)
			(size 1.27 1.27)
			(drill 0.889)
			(layers "*.Cu" "*.Mask")
			(remove_unused_layers no)
			(net "LOW_HEX_3")
			(clearance 0.1651)
			(thermal_gap 0.1651)
		)
		(pad "5" thru_hole circle
			(at -2.00025 0.99949 180)
			(size 1.27 1.27)
			(drill 0.889)
			(layers "*.Cu" "*.Mask")
			(remove_unused_layers no)
			(net "HIGH_HEX_0")
			(clearance 0.1651)
			(thermal_gap 0.1651)
		)
		(pad "6" thru_hole circle
			(at -2.00025 -0.99949 180)
			(size 1.27 1.27)
			(drill 0.889)
			(layers "*.Cu" "*.Mask")
			(remove_unused_layers no)
			(net "HIGH_HEX_1")
			(clearance 0.1651)
			(thermal_gap 0.1651)
		)
		(pad "7" thru_hole circle
			(at 0 0.99949 180)
			(size 1.27 1.27)
			(drill 0.889)
			(layers "*.Cu" "*.Mask")
			(remove_unused_layers no)
			(net "HIGH_HEX_2")
			(clearance 0.1651)
			(thermal_gap 0.1651)
		)
		(pad "8" thru_hole circle
			(at 0 -0.99949 180)
			(size 1.27 1.27)
			(drill 0.889)
			(layers "*.Cu" "*.Mask")
			(remove_unused_layers no)
			(net "HIGH_HEX_3")
			(clearance 0.1651)
			(thermal_gap 0.1651)
		)
		(pad "9" thru_hole circle
			(at 2.00025 0.99949 180)
			(size 1.27 1.27)
			(drill 0.889)
			(layers "*.Cu" "*.Mask")
			(remove_unused_layers no)
			(net "DEBUG_CARD_TX")
			(clearance 0.1651)
			(thermal_gap 0.1651)
		)
		(pad "10" thru_hole circle
			(at 2.00025 -0.99949 180)
			(size 1.27 1.27)
			(drill 0.889)
			(layers "*.Cu" "*.Mask")
			(remove_unused_layers no)
			(net "DEBUG_CARD_RX")
			(clearance 0.1651)
			(thermal_gap 0.1651)
		)
		(pad "11" thru_hole circle
			(at 4.0005 0.99949 180)
			(size 1.27 1.27)
			(drill 0.889)
			(layers "*.Cu" "*.Mask")
			(remove_unused_layers no)
			(net "DP_RST_N")
			(clearance 0.1651)
			(thermal_gap 0.1651)
		)
		(pad "12" thru_hole circle
			(at 4.0005 -0.99949 180)
			(size 1.27 1.27)
			(drill 0.889)
			(layers "*.Cu" "*.Mask")
			(remove_unused_layers no)
			(net "UART_COUNT")
			(clearance 0.1651)
			(thermal_gap 0.1651)
		)
		(pad "13" thru_hole circle
			(at 5.99948 0.99949 180)
			(size 1.27 1.27)
			(drill 0.889)
			(layers "*.Cu" "*.Mask")
			(remove_unused_layers no)
			(net "GND")
			(clearance 0.1651)
			(thermal_gap 0.1651)
		)
		(pad "14" thru_hole circle
			(at 5.99948 -0.99949 180)
			(size 1.27 1.27)
			(drill 0.889)
			(layers "*.Cu" "*.Mask")
			(remove_unused_layers no)
			(net "P5V_STBY")
			(clearance 0.1651)
			(thermal_gap 0.1651)
		)
	)
	(footprint ""
		(layer "F.Cu")
		(at 221.069408 -188.3283 90)
		(property "Reference" "C4120"
			(at 0 0 90)
			(layer "F.SilkS")
			(hide yes)
			(effects
				(font
					(size 1.27 1.27)
				)
			)
		)
		(property "Value" "SCD1U25V3KX-GP"
			(at 0 -2.8194 90)
			(unlocked yes)
			(layer "F.Fab")
			(hide yes)
			(effects
				(font
					(size 1.016 1.016)
					(thickness 0.1524)
				)
			)
		)
		(property "Device Type" "C603H36"
			(at 0 -4.3434 90)
			(unlocked yes)
			(layer "F.Fab")
			(hide yes)
			(effects
				(font
					(size 1.016 1.016)
					(thickness 0.1524)
				)
			)
		)
		(duplicate_pad_numbers_are_jumpers no)
		(fp_line
			(start 0.508 0)
			(end -0.508 0)
			(stroke
				(width 0.2032)
				(type default)
			)
			(layer "F.SilkS")
		)
		(fp_rect
			(start -0.5842 1.3335)
			(end 0.5842 -1.3335)
			(stroke
				(width 0)
				(type default)
			)
			(fill no)
			(layer "F.CrtYd")
		)
		(fp_rect
			(start -0.5842 1.3335)
			(end 0.5842 -1.3335)
			(stroke
				(width 0)
				(type default)
			)
			(fill no)
			(layer "F.Fab")
		)
		(pad "1" smd custom
			(at 0 -0.762 90)
			(size 0.2159 0.2159)
			(layers "F.Cu" "F.Mask" "F.Paste")
			(net "GND")
			(options
				(clearance outline)
				(anchor circle)
			)
			(primitives
				(gr_poly
					(pts
						(arc
							(start -0.3302 -0.4318)
							(mid -0.402042 -0.402042)
							(end -0.4318 -0.3302)
						)
						(arc
							(start -0.4318 0.3302)
							(mid -0.402042 0.402042)
							(end -0.3302 0.4318)
						)
						(arc
							(start 0.3302 0.4318)
							(mid 0.402042 0.402042)
							(end 0.4318 0.3302)
						)
						(arc
							(start 0.4318 -0.3302)
							(mid 0.402042 -0.402042)
							(end 0.3302 -0.4318)
						)
					)
					(width 0)
					(fill yes)
				)
			)
		)
		(pad "2" smd custom
			(at 0 0.762 90)
			(size 0.2159 0.2159)
			(layers "F.Cu" "F.Mask" "F.Paste")
			(net "SSD_PWREN3_R")
			(options
				(clearance outline)
				(anchor circle)
			)
			(primitives
				(gr_poly
					(pts
						(arc
							(start -0.3302 -0.4318)
							(mid -0.402042 -0.402042)
							(end -0.4318 -0.3302)
						)
						(arc
							(start -0.4318 0.3302)
							(mid -0.402042 0.402042)
							(end -0.3302 0.4318)
						)
						(arc
							(start 0.3302 0.4318)
							(mid 0.402042 0.402042)
							(end 0.4318 0.3302)
						)
						(arc
							(start 0.4318 -0.3302)
							(mid 0.402042 -0.402042)
							(end 0.3302 -0.4318)
						)
					)
					(width 0)
					(fill yes)
				)
			)
		)
	)
)
